# T6G (Grand Teton) — schematic netlist excerpt (pin names and nets, part order shuffled) for the footprints in the layout excerpt that follows; sources: Cadence DE-HDL packaged netlist, KiCad conversion of 04192023_DAF0TMB3IC0_F0TG_MB_C_brd_V02_OCP.brd

C329  Q_CAP  22UF 4V 20% X6S  pkg C0402  page 334 : A = P0V9_CPU1_RT1_2A ; B = GND
R6749  Q_RES  0 5% CHIP  pkg 0201LF  page 184 : A = SMB_RT_CPU1_P2_R_SCL ; B = SMB_RT_CPU1_P2_SCL
R3099  Q_RES  130 1% CHIP  pkg 0402LF  page 256 : A = LED_PWRGD_PVDD11_S3_P1_R ; B = P3V3_AUX

(kicad_pcb
	(version 20260206)
	(generator "pcbnew")
	(generator_version "10.0")
	(general
		(thickness 1.6)
		(legacy_teardrops no)
	)
	(paper "A4")
	(title_block
		(title "04192023_DAF0TMB3IC0_F0TG_MB_C_brd_V02_OCP.brd")
		(comment 1 "Grand Teton / footprints 6687-6689 of 8354")
	)
	(layers
		(0 "F.Cu" signal "TOP")
		(4 "In1.Cu" signal "GND")
		(6 "In2.Cu" signal "IN1")
		(8 "In3.Cu" signal "GND1")
		(10 "In4.Cu" signal "IN2")
		(12 "In5.Cu" signal "GND2")
		(14 "In6.Cu" signal "IN3")
		(16 "In7.Cu" signal "GND3")
		(18 "In8.Cu" signal "VCC")
		(20 "In9.Cu" signal "VCC1")
		(22 "In10.Cu" signal "GND4")
		(24 "In11.Cu" signal "IN4")
		(26 "In12.Cu" signal "GND5")
		(28 "In13.Cu" signal "IN5")
		(30 "In14.Cu" signal "GND6")
		(32 "In15.Cu" signal "IN6")
		(34 "In16.Cu" signal "GND7")
		(2 "B.Cu" signal "BOTTOM")
		(9 "F.Adhes" user "F.Adhesive")
		(11 "B.Adhes" user "B.Adhesive")
		(13 "F.Paste" user "Package Geometry/Pastemask Top")
		(15 "B.Paste" user "Package Geometry/Pastemask Bottom")
		(5 "F.SilkS" user "Ref Des/Silkscreen Top")
		(7 "B.SilkS" user "Ref Des/Silkscreen Bottom")
		(1 "F.Mask" user "Board Geometry/Soldermask Top")
		(3 "B.Mask" user "Board Geometry/Soldermask Bottom")
		(17 "Dwgs.User" user "User.Drawings")
		(19 "Cmts.User" user "User.Comments")
		(21 "Eco1.User" user "User.Eco1")
		(23 "Eco2.User" user "User.Eco2")
		(25 "Edge.Cuts" user "Board Geometry/Outline")
		(27 "Margin" user)
		(31 "F.CrtYd" user "Package Geometry/Place Bound Top")
		(29 "B.CrtYd" user "Package Geometry/Place Bound Bottom")
		(35 "F.Fab" user "Ref Des/Assembly Top")
		(33 "B.Fab" user "Ref Des/Assembly Bottom")
	)
	(footprint ""
		(layer "B.Cu")
		(at 81.118964 -390.560052 90)
		(property "Reference" "C329"
			(at 0 0 90)
			(layer "B.SilkS")
			(hide yes)
			(effects
				(font
					(size 1.27 1.27)
				)
				(justify mirror)
			)
		)
		(property "Value" ""
			(at 0 0 90)
			(layer "B.Fab")
			(effects
				(font
					(size 1.27 1.27)
				)
				(justify mirror)
			)
		)
		(duplicate_pad_numbers_are_jumpers no)
		(fp_line
			(start 0.7874 -0.4064)
			(end -0.7874 -0.4064)
			(stroke
				(width 0.1524)
				(type default)
			)
			(layer "B.SilkS")
		)
		(fp_line
			(start -0.7874 -0.4064)
			(end -0.7874 0.4064)
			(stroke
				(width 0.1524)
				(type default)
			)
			(layer "B.SilkS")
		)
		(fp_line
			(start 0.7874 0.4064)
			(end 0.7874 -0.4064)
			(stroke
				(width 0.1524)
				(type default)
			)
			(layer "B.SilkS")
		)
		(fp_line
			(start -0.7874 0.4064)
			(end 0.7874 0.4064)
			(stroke
				(width 0.1524)
				(type default)
			)
			(layer "B.SilkS")
		)
		(fp_line
			(start 0.67945 -0.305054)
			(end 0.12065 -0.305054)
			(stroke
				(width 0.1)
				(type default)
			)
			(layer "B.Fab")
		)
		(fp_line
			(start 0.12065 -0.305054)
			(end 0.12065 -0.2794)
			(stroke
				(width 0.1)
				(type default)
			)
			(layer "B.Fab")
		)
		(fp_line
			(start -0.12065 -0.3048)
			(end -0.67945 -0.3048)
			(stroke
				(width 0.1)
				(type default)
			)
			(layer "B.Fab")
		)
		(fp_line
			(start -0.67945 -0.3048)
			(end -0.67945 0.3048)
			(stroke
				(width 0.1)
				(type default)
			)
			(layer "B.Fab")
		)
		(fp_line
			(start 0.12065 -0.2794)
			(end -0.12065 -0.2794)
			(stroke
				(width 0.1)
				(type default)
			)
			(layer "B.Fab")
		)
		(fp_line
			(start -0.12065 -0.2794)
			(end -0.12065 -0.3048)
			(stroke
				(width 0.1)
				(type default)
			)
			(layer "B.Fab")
		)
		(fp_line
			(start 0.12065 0.2794)
			(end 0.12065 0.3048)
			(stroke
				(width 0.1)
				(type default)
			)
			(layer "B.Fab")
		)
		(fp_line
			(start -0.120396 0.2794)
			(end 0.12065 0.2794)
			(stroke
				(width 0.1)
				(type default)
			)
			(layer "B.Fab")
		)
		(fp_line
			(start 0.67945 0.3048)
			(end 0.67945 -0.305054)
			(stroke
				(width 0.1)
				(type default)
			)
			(layer "B.Fab")
		)
		(fp_line
			(start 0.12065 0.3048)
			(end 0.67945 0.3048)
			(stroke
				(width 0.1)
				(type default)
			)
			(layer "B.Fab")
		)
		(fp_line
			(start -0.120396 0.3048)
			(end -0.120396 0.2794)
			(stroke
				(width 0.1)
				(type default)
			)
			(layer "B.Fab")
		)
		(fp_line
			(start -0.67945 0.3048)
			(end -0.120396 0.3048)
			(stroke
				(width 0.1)
				(type default)
			)
			(layer "B.Fab")
		)
		(pad "1" smd circle
			(at 0.40005 0 270)
			(size 0 0)
			(layers "B.Cu" "B.Mask" "B.Paste")
			(net "P0V9_CPU1_RT1_2A")
		)
		(pad "2" smd circle
			(at -0.40005 0 270)
			(size 0 0)
			(layers "B.Cu" "B.Mask" "B.Paste")
			(net "GND")
		)
	)
	(footprint ""
		(layer "B.Cu")
		(at 218.059 -341.884 180)
		(property "Reference" "R6749"
			(at 0 0 0)
			(layer "B.SilkS")
			(hide yes)
			(effects
				(font
					(size 1.27 1.27)
				)
				(justify mirror)
			)
		)
		(property "Value" ""
			(at 0 0 0)
			(layer "B.Fab")
			(effects
				(font
					(size 1.27 1.27)
				)
				(justify mirror)
			)
		)
		(duplicate_pad_numbers_are_jumpers no)
		(fp_line
			(start 0.32512 0.175006)
			(end 0.32512 -0.175006)
			(stroke
				(width 0.1)
				(type default)
			)
			(layer "B.Fab")
		)
		(fp_line
			(start 0.32512 -0.175006)
			(end -0.32512 -0.175006)
			(stroke
				(width 0.1)
				(type default)
			)
			(layer "B.Fab")
		)
		(fp_line
			(start -0.32512 0.175006)
			(end 0.32512 0.175006)
			(stroke
				(width 0.1)
				(type default)
			)
			(layer "B.Fab")
		)
		(fp_line
			(start -0.32512 -0.175006)
			(end -0.32512 0.175006)
			(stroke
				(width 0.1)
				(type default)
			)
			(layer "B.Fab")
		)
		(pad "1" smd rect
			(at 0.2667 0)
			(size 0.3048 0.381)
			(layers "B.Cu" "B.Mask" "B.Paste")
			(net "SMB_RT_CPU1_P2_R_SCL")
		)
		(pad "2" smd rect
			(at -0.2667 0 180)
			(size 0.3048 0.381)
			(layers "B.Cu" "B.Mask" "B.Paste")
			(net "SMB_RT_CPU1_P2_SCL")
		)
	)
	(footprint ""
		(layer "B.Cu")
		(at 344.955876 -66.708782 90)
		(property "Reference" "R3099"
			(at 0 0 90)
			(layer "B.SilkS")
			(hide yes)
			(effects
				(font
					(size 1.27 1.27)
				)
				(justify mirror)
			)
		)
		(property "Value" ""
			(at 0 0 90)
			(layer "B.Fab")
			(effects
				(font
					(size 1.27 1.27)
				)
				(justify mirror)
			)
		)
		(duplicate_pad_numbers_are_jumpers no)
		(fp_line
			(start 0.7874 -0.4064)
			(end -0.7874 -0.4064)
			(stroke
				(width 0.1524)
				(type default)
			)
			(layer "B.SilkS")
		)
		(fp_line
			(start -0.7874 -0.4064)
			(end -0.7874 0.4064)
			(stroke
				(width 0.1524)
				(type default)
			)
			(layer "B.SilkS")
		)
		(fp_line
			(start 0.7874 0.4064)
			(end 0.7874 -0.4064)
			(stroke
				(width 0.1524)
				(type default)
			)
			(layer "B.SilkS")
		)
		(fp_line
			(start -0.7874 0.4064)
			(end 0.7874 0.4064)
			(stroke
				(width 0.1524)
				(type default)
			)
			(layer "B.SilkS")
		)
		(fp_line
			(start 0.67945 -0.305054)
			(end 0.12065 -0.305054)
			(stroke
				(width 0.1)
				(type default)
			)
			(layer "B.Fab")
		)
		(fp_line
			(start 0.12065 -0.305054)
			(end 0.12065 -0.2794)
			(stroke
				(width 0.1)
				(type default)
			)
			(layer "B.Fab")
		)
		(fp_line
			(start -0.12065 -0.3048)
			(end -0.67945 -0.3048)
			(stroke
				(width 0.1)
				(type default)
			)
			(layer "B.Fab")
		)
		(fp_line
			(start -0.67945 -0.3048)
			(end -0.67945 0.3048)
			(stroke
				(width 0.1)
				(type default)
			)
			(layer "B.Fab")
		)
		(fp_line
			(start 0.12065 -0.2794)
			(end -0.12065 -0.2794)
			(stroke
				(width 0.1)
				(type default)
			)
			(layer "B.Fab")
		)
		(fp_line
			(start -0.12065 -0.2794)
			(end -0.12065 -0.3048)
			(stroke
				(width 0.1)
				(type default)
			)
			(layer "B.Fab")
		)
		(fp_line
			(start 0.12065 0.2794)
			(end 0.12065 0.3048)
			(stroke
				(width 0.1)
				(type default)
			)
			(layer "B.Fab")
		)
		(fp_line
			(start -0.120396 0.2794)
			(end 0.12065 0.2794)
			(stroke
				(width 0.1)
				(type default)
			)
			(layer "B.Fab")
		)
		(fp_line
			(start 0.67945 0.3048)
			(end 0.67945 -0.305054)
			(stroke
				(width 0.1)
				(type default)
			)
			(layer "B.Fab")
		)
		(fp_line
			(start 0.12065 0.3048)
			(end 0.67945 0.3048)
			(stroke
				(width 0.1)
				(type default)
			)
			(layer "B.Fab")
		)
		(fp_line
			(start -0.120396 0.3048)
			(end -0.120396 0.2794)
			(stroke
				(width 0.1)
				(type default)
			)
			(layer "B.Fab")
		)
		(fp_line
			(start -0.67945 0.3048)
			(end -0.120396 0.3048)
			(stroke
				(width 0.1)
				(type default)
			)
			(layer "B.Fab")
		)
		(pad "1" smd circle
			(at 0.40005 0 270)
			(size 0 0)
			(layers "B.Cu" "B.Mask" "B.Paste")
			(net "LED_PWRGD_PVDD11_S3_P1_R")
		)
		(pad "2" smd circle
			(at -0.40005 0 270)
			(size 0 0)
			(layers "B.Cu" "B.Mask" "B.Paste")
			(net "P3V3_AUX")
		)
	)
)
